# S9S_MB_2U (Grand Teton) — schematic netlist excerpt (pin names and nets, part order shuffled) for the footprints in the layout excerpt that follows; sources: Cadence DE-HDL packaged netlist, KiCad conversion of 03242023_DA0F0TMBIJ0_F0T_Motherboard_J_brd_V01_OCP.brd

PC2205  Q_CAP  2.2UF 16V 20% X7R  pkg C0603  page 193 : A = P12V_E1S_AVIN_PD_0 ; B = GND
C1278  Q_CAP  0.1UF 25V 10% X7R  pkg 0402  page 191 : A = P12V_E1S_0 ; B = GND
C101  Q_CAP  47UF 4V 20% X6S  pkg C0805  page 74 : A = PVCCIN_CPU0 ; B = GND

(kicad_pcb
	(version 20260206)
	(generator "pcbnew")
	(generator_version "10.0")
	(general
		(thickness 1.6)
		(legacy_teardrops no)
	)
	(paper "A4")
	(title_block
		(title "03242023_DA0F0TMBIJ0_F0T_Motherboard_J_brd_V01_OCP.brd")
		(comment 1 "Grand Teton / footprints 370-372 of 6105")
	)
	(layers
		(0 "F.Cu" signal "TOP")
		(4 "In1.Cu" signal "GND")
		(6 "In2.Cu" signal "IN1")
		(8 "In3.Cu" signal "GND1")
		(10 "In4.Cu" signal "IN2")
		(12 "In5.Cu" signal "GND2")
		(14 "In6.Cu" signal "IN3")
		(16 "In7.Cu" signal "GND3")
		(18 "In8.Cu" signal "VCC")
		(20 "In9.Cu" signal "VCC1")
		(22 "In10.Cu" signal "GND4")
		(24 "In11.Cu" signal "IN4")
		(26 "In12.Cu" signal "GND5")
		(28 "In13.Cu" signal "IN5")
		(30 "In14.Cu" signal "GND6")
		(32 "In15.Cu" signal "IN6")
		(34 "In16.Cu" signal "GND7")
		(2 "B.Cu" signal "BOTTOM")
		(9 "F.Adhes" user "F.Adhesive")
		(11 "B.Adhes" user "B.Adhesive")
		(13 "F.Paste" user "Package Geometry/Pastemask Top")
		(15 "B.Paste" user "Package Geometry/Pastemask Bottom")
		(5 "F.SilkS" user "Ref Des/Silkscreen Top")
		(7 "B.SilkS" user "Ref Des/Silkscreen Bottom")
		(1 "F.Mask" user "Board Geometry/Soldermask Top")
		(3 "B.Mask" user "Board Geometry/Soldermask Bottom")
		(17 "Dwgs.User" user "User.Drawings")
		(19 "Cmts.User" user "User.Comments")
		(21 "Eco1.User" user "User.Eco1")
		(23 "Eco2.User" user "User.Eco2")
		(25 "Edge.Cuts" user "Board Geometry/Outline")
		(27 "Margin" user)
		(31 "F.CrtYd" user "Package Geometry/Place Bound Top")
		(29 "B.CrtYd" user "Package Geometry/Place Bound Bottom")
		(35 "F.Fab" user "Ref Des/Assembly Top")
		(33 "B.Fab" user "Ref Des/Assembly Bottom")
	)
	(footprint ""
		(layer "F.Cu")
		(at 362.89488 -294.01008)
		(property "Reference" "C101"
			(at 0 0 0)
			(layer "F.SilkS")
			(hide yes)
			(effects
				(font
					(size 1.27 1.27)
				)
			)
		)
		(property "Value" ""
			(at 0 0 0)
			(layer "F.Fab")
			(effects
				(font
					(size 1.27 1.27)
				)
			)
		)
		(duplicate_pad_numbers_are_jumpers no)
		(fp_line
			(start -1.524 -0.762)
			(end 1.524 -0.762)
			(stroke
				(width 0.1524)
				(type default)
			)
			(layer "F.SilkS")
		)
		(fp_line
			(start -1.524 0.762)
			(end -1.524 -0.762)
			(stroke
				(width 0.1524)
				(type default)
			)
			(layer "F.SilkS")
		)
		(fp_line
			(start 1.524 -0.762)
			(end 1.524 0.762)
			(stroke
				(width 0.1524)
				(type default)
			)
			(layer "F.SilkS")
		)
		(fp_line
			(start 1.524 0.762)
			(end -1.524 0.762)
			(stroke
				(width 0.1524)
				(type default)
			)
			(layer "F.SilkS")
		)
		(fp_line
			(start -1.1049 -0.724916)
			(end -1.1049 0.724916)
			(stroke
				(width 0.1)
				(type default)
			)
			(layer "F.Fab")
		)
		(fp_line
			(start -1.1049 0.724916)
			(end 1.1049 0.724916)
			(stroke
				(width 0.1)
				(type default)
			)
			(layer "F.Fab")
		)
		(fp_line
			(start 1.1049 -0.724916)
			(end -1.1049 -0.724916)
			(stroke
				(width 0.1)
				(type default)
			)
			(layer "F.Fab")
		)
		(fp_line
			(start 1.1049 0.724916)
			(end 1.1049 -0.724916)
			(stroke
				(width 0.1)
				(type default)
			)
			(layer "F.Fab")
		)
		(pad "1" smd rect
			(at -0.889 0 180)
			(size 1.016 1.27)
			(layers "F.Cu" "F.Mask" "F.Paste")
			(net "PVCCIN_CPU0")
		)
		(pad "2" smd rect
			(at 0.889 0 180)
			(size 1.016 1.27)
			(layers "F.Cu" "F.Mask" "F.Paste")
			(net "GND")
		)
	)
	(footprint ""
		(layer "F.Cu")
		(at 244.128798 -50.126646 90)
		(property "Reference" "C1278"
			(at 0 0 90)
			(layer "F.SilkS")
			(hide yes)
			(effects
				(font
					(size 1.27 1.27)
				)
			)
		)
		(property "Value" ""
			(at 0 0 90)
			(layer "F.Fab")
			(effects
				(font
					(size 1.27 1.27)
				)
			)
		)
		(duplicate_pad_numbers_are_jumpers no)
		(fp_line
			(start 0.7874 -0.4064)
			(end 0.7874 0.4064)
			(stroke
				(width 0.1524)
				(type default)
			)
			(layer "F.SilkS")
		)
		(fp_line
			(start -0.7874 -0.4064)
			(end 0.7874 -0.4064)
			(stroke
				(width 0.1524)
				(type default)
			)
			(layer "F.SilkS")
		)
		(fp_line
			(start 0.7874 0.4064)
			(end -0.7874 0.4064)
			(stroke
				(width 0.1524)
				(type default)
			)
			(layer "F.SilkS")
		)
		(fp_line
			(start -0.7874 0.4064)
			(end -0.7874 -0.4064)
			(stroke
				(width 0.1524)
				(type default)
			)
			(layer "F.SilkS")
		)
		(fp_line
			(start -0.12065 -0.305054)
			(end -0.12065 -0.2794)
			(stroke
				(width 0.1)
				(type default)
			)
			(layer "F.Fab")
		)
		(fp_line
			(start -0.67945 -0.305054)
			(end -0.12065 -0.305054)
			(stroke
				(width 0.1)
				(type default)
			)
			(layer "F.Fab")
		)
		(fp_line
			(start 0.67945 -0.3048)
			(end 0.67945 0.3048)
			(stroke
				(width 0.1)
				(type default)
			)
			(layer "F.Fab")
		)
		(fp_line
			(start 0.12065 -0.3048)
			(end 0.67945 -0.3048)
			(stroke
				(width 0.1)
				(type default)
			)
			(layer "F.Fab")
		)
		(fp_line
			(start 0.12065 -0.2794)
			(end 0.12065 -0.3048)
			(stroke
				(width 0.1)
				(type default)
			)
			(layer "F.Fab")
		)
		(fp_line
			(start -0.12065 -0.2794)
			(end 0.12065 -0.2794)
			(stroke
				(width 0.1)
				(type default)
			)
			(layer "F.Fab")
		)
		(fp_line
			(start 0.120396 0.2794)
			(end -0.12065 0.2794)
			(stroke
				(width 0.1)
				(type default)
			)
			(layer "F.Fab")
		)
		(fp_line
			(start -0.12065 0.2794)
			(end -0.12065 0.3048)
			(stroke
				(width 0.1)
				(type default)
			)
			(layer "F.Fab")
		)
		(fp_line
			(start 0.67945 0.3048)
			(end 0.120396 0.3048)
			(stroke
				(width 0.1)
				(type default)
			)
			(layer "F.Fab")
		)
		(fp_line
			(start 0.120396 0.3048)
			(end 0.120396 0.2794)
			(stroke
				(width 0.1)
				(type default)
			)
			(layer "F.Fab")
		)
		(fp_line
			(start -0.12065 0.3048)
			(end -0.67945 0.3048)
			(stroke
				(width 0.1)
				(type default)
			)
			(layer "F.Fab")
		)
		(fp_line
			(start -0.67945 0.3048)
			(end -0.67945 -0.305054)
			(stroke
				(width 0.1)
				(type default)
			)
			(layer "F.Fab")
		)
		(pad "1" smd circle
			(at -0.40005 0 90)
			(size 0 0)
			(layers "F.Cu" "F.Mask" "F.Paste")
			(net "P12V_E1S_0")
		)
		(pad "2" smd circle
			(at 0.40005 0 90)
			(size 0 0)
			(layers "F.Cu" "F.Mask" "F.Paste")
			(net "GND")
		)
	)
	(footprint ""
		(layer "F.Cu")
		(at 250.77039 -53.424582 90)
		(property "Reference" "PC2205"
			(at 0 0 90)
			(layer "F.SilkS")
			(hide yes)
			(effects
				(font
					(size 1.27 1.27)
				)
			)
		)
		(property "Value" ""
			(at 0 0 90)
			(layer "F.Fab")
			(effects
				(font
					(size 1.27 1.27)
				)
			)
		)
		(duplicate_pad_numbers_are_jumpers no)
		(fp_line
			(start 1.2954 -0.5842)
			(end 1.2954 0.5842)
			(stroke
				(width 0.1524)
				(type default)
			)
			(layer "F.SilkS")
		)
		(fp_line
			(start 0 -0.5842)
			(end 0 0.5842)
			(stroke
				(width 0.1524)
				(type default)
			)
			(layer "F.SilkS")
		)
		(fp_line
			(start -1.2954 -0.5842)
			(end 1.2954 -0.5842)
			(stroke
				(width 0.1524)
				(type default)
			)
			(layer "F.SilkS")
		)
		(fp_line
			(start 1.2954 0.5842)
			(end -1.2954 0.5842)
			(stroke
				(width 0.1524)
				(type default)
			)
			(layer "F.SilkS")
		)
		(fp_line
			(start -1.2954 0.5842)
			(end -1.2954 -0.5842)
			(stroke
				(width 0.1524)
				(type default)
			)
			(layer "F.SilkS")
		)
		(fp_line
			(start 0.8636 -0.4572)
			(end 0.8636 -0.4064)
			(stroke
				(width 0.1)
				(type default)
			)
			(layer "F.Fab")
		)
		(fp_line
			(start -0.8636 -0.4572)
			(end 0.8636 -0.4572)
			(stroke
				(width 0.1)
				(type default)
			)
			(layer "F.Fab")
		)
		(fp_line
			(start 1.1938 -0.4064)
			(end 1.1938 0.4064)
			(stroke
				(width 0.1)
				(type default)
			)
			(layer "F.Fab")
		)
		(fp_line
			(start 0.8636 -0.4064)
			(end 1.1938 -0.4064)
			(stroke
				(width 0.1)
				(type default)
			)
			(layer "F.Fab")
		)
		(fp_line
			(start -0.8636 -0.4064)
			(end -0.8636 -0.4572)
			(stroke
				(width 0.1)
				(type default)
			)
			(layer "F.Fab")
		)
		(fp_line
			(start -1.1938 -0.4064)
			(end -0.8636 -0.4064)
			(stroke
				(width 0.1)
				(type default)
			)
			(layer "F.Fab")
		)
		(fp_line
			(start 1.1938 0.4064)
			(end 0.8636 0.4064)
			(stroke
				(width 0.1)
				(type default)
			)
			(layer "F.Fab")
		)
		(fp_line
			(start 0.8636 0.4064)
			(end 0.8636 0.4572)
			(stroke
				(width 0.1)
				(type default)
			)
			(layer "F.Fab")
		)
		(fp_line
			(start -0.8636 0.4064)
			(end -1.1938 0.4064)
			(stroke
				(width 0.1)
				(type default)
			)
			(layer "F.Fab")
		)
		(fp_line
			(start -1.1938 0.4064)
			(end -1.1938 -0.4064)
			(stroke
				(width 0.1)
				(type default)
			)
			(layer "F.Fab")
		)
		(fp_line
			(start 0.8636 0.4572)
			(end -0.8636 0.4572)
			(stroke
				(width 0.1)
				(type default)
			)
			(layer "F.Fab")
		)
		(fp_line
			(start -0.8636 0.4572)
			(end -0.8636 0.4064)
			(stroke
				(width 0.1)
				(type default)
			)
			(layer "F.Fab")
		)
		(pad "1" smd rect
			(at -0.7366 0)
			(size 0.7112 0.8128)
			(layers "F.Cu" "F.Mask" "F.Paste")
			(net "P12V_E1S_AVIN_PD_0")
		)
		(pad "2" smd rect
			(at 0.7366 0)
			(size 0.7112 0.8128)
			(layers "F.Cu" "F.Mask" "F.Paste")
			(net "GND")
		)
	)
)
